# T6G (Grand Teton) — schematic netlist excerpt (pin names and nets, part order shuffled) for the footprints in the layout excerpt that follows; sources: Cadence DE-HDL packaged netlist, KiCad conversion of 04192023_DAF0TMB3IC0_F0TG_MB_C_brd_V02_OCP.brd

C2527  Q_CAP  22UF 4V 20% X6S  pkg C0402  page 70 : A = PVDDCR_SOC_P0 ; B = GND
R3305  Q_RES  0 5% CHIP  pkg 0402LF  page 143 : A = OCP_SFF_RBT_ARB_IN_MUX1 ; B = OCP_SFF_RBT_ARB_IN_MUX1_R

(kicad_pcb
	(version 20260206)
	(generator "pcbnew")
	(generator_version "10.0")
	(general
		(thickness 1.6)
		(legacy_teardrops no)
	)
	(paper "A4")
	(title_block
		(title "04192023_DAF0TMB3IC0_F0TG_MB_C_brd_V02_OCP.brd")
		(comment 1 "Grand Teton / footprints 3764-3765 of 8354")
	)
	(layers
		(0 "F.Cu" signal "TOP")
		(4 "In1.Cu" signal "GND")
		(6 "In2.Cu" signal "IN1")
		(8 "In3.Cu" signal "GND1")
		(10 "In4.Cu" signal "IN2")
		(12 "In5.Cu" signal "GND2")
		(14 "In6.Cu" signal "IN3")
		(16 "In7.Cu" signal "GND3")
		(18 "In8.Cu" signal "VCC")
		(20 "In9.Cu" signal "VCC1")
		(22 "In10.Cu" signal "GND4")
		(24 "In11.Cu" signal "IN4")
		(26 "In12.Cu" signal "GND5")
		(28 "In13.Cu" signal "IN5")
		(30 "In14.Cu" signal "GND6")
		(32 "In15.Cu" signal "IN6")
		(34 "In16.Cu" signal "GND7")
		(2 "B.Cu" signal "BOTTOM")
		(9 "F.Adhes" user "F.Adhesive")
		(11 "B.Adhes" user "B.Adhesive")
		(13 "F.Paste" user "Package Geometry/Pastemask Top")
		(15 "B.Paste" user "Package Geometry/Pastemask Bottom")
		(5 "F.SilkS" user "Ref Des/Silkscreen Top")
		(7 "B.SilkS" user "Ref Des/Silkscreen Bottom")
		(1 "F.Mask" user "Board Geometry/Soldermask Top")
		(3 "B.Mask" user "Board Geometry/Soldermask Bottom")
		(17 "Dwgs.User" user "User.Drawings")
		(19 "Cmts.User" user "User.Comments")
		(21 "Eco1.User" user "User.Eco1")
		(23 "Eco2.User" user "User.Eco2")
		(25 "Edge.Cuts" user "Board Geometry/Outline")
		(27 "Margin" user)
		(31 "F.CrtYd" user "Package Geometry/Place Bound Top")
		(29 "B.CrtYd" user "Package Geometry/Place Bound Bottom")
		(35 "F.Fab" user "Ref Des/Assembly Top")
		(33 "B.Fab" user "Ref Des/Assembly Bottom")
	)
	(footprint ""
		(layer "F.Cu")
		(at 361.046014 -258.795012)
		(property "Reference" "C2527"
			(at 0 0 0)
			(layer "F.SilkS")
			(hide yes)
			(effects
				(font
					(size 1.27 1.27)
				)
			)
		)
		(property "Value" ""
			(at 0 0 0)
			(layer "F.Fab")
			(effects
				(font
					(size 1.27 1.27)
				)
			)
		)
		(duplicate_pad_numbers_are_jumpers no)
		(fp_line
			(start -0.7874 -0.4064)
			(end 0.7874 -0.4064)
			(stroke
				(width 0.1524)
				(type default)
			)
			(layer "F.SilkS")
		)
		(fp_line
			(start -0.7874 0.4064)
			(end -0.7874 -0.4064)
			(stroke
				(width 0.1524)
				(type default)
			)
			(layer "F.SilkS")
		)
		(fp_line
			(start 0.7874 -0.4064)
			(end 0.7874 0.4064)
			(stroke
				(width 0.1524)
				(type default)
			)
			(layer "F.SilkS")
		)
		(fp_line
			(start 0.7874 0.4064)
			(end -0.7874 0.4064)
			(stroke
				(width 0.1524)
				(type default)
			)
			(layer "F.SilkS")
		)
		(fp_line
			(start -0.67945 -0.305054)
			(end -0.12065 -0.305054)
			(stroke
				(width 0.1)
				(type default)
			)
			(layer "F.Fab")
		)
		(fp_line
			(start -0.67945 0.3048)
			(end -0.67945 -0.305054)
			(stroke
				(width 0.1)
				(type default)
			)
			(layer "F.Fab")
		)
		(fp_line
			(start -0.12065 -0.305054)
			(end -0.12065 -0.2794)
			(stroke
				(width 0.1)
				(type default)
			)
			(layer "F.Fab")
		)
		(fp_line
			(start -0.12065 -0.2794)
			(end 0.12065 -0.2794)
			(stroke
				(width 0.1)
				(type default)
			)
			(layer "F.Fab")
		)
		(fp_line
			(start -0.12065 0.2794)
			(end -0.12065 0.3048)
			(stroke
				(width 0.1)
				(type default)
			)
			(layer "F.Fab")
		)
		(fp_line
			(start -0.12065 0.3048)
			(end -0.67945 0.3048)
			(stroke
				(width 0.1)
				(type default)
			)
			(layer "F.Fab")
		)
		(fp_line
			(start 0.120396 0.2794)
			(end -0.12065 0.2794)
			(stroke
				(width 0.1)
				(type default)
			)
			(layer "F.Fab")
		)
		(fp_line
			(start 0.120396 0.3048)
			(end 0.120396 0.2794)
			(stroke
				(width 0.1)
				(type default)
			)
			(layer "F.Fab")
		)
		(fp_line
			(start 0.12065 -0.3048)
			(end 0.67945 -0.3048)
			(stroke
				(width 0.1)
				(type default)
			)
			(layer "F.Fab")
		)
		(fp_line
			(start 0.12065 -0.2794)
			(end 0.12065 -0.3048)
			(stroke
				(width 0.1)
				(type default)
			)
			(layer "F.Fab")
		)
		(fp_line
			(start 0.67945 -0.3048)
			(end 0.67945 0.3048)
			(stroke
				(width 0.1)
				(type default)
			)
			(layer "F.Fab")
		)
		(fp_line
			(start 0.67945 0.3048)
			(end 0.120396 0.3048)
			(stroke
				(width 0.1)
				(type default)
			)
			(layer "F.Fab")
		)
		(pad "1" smd circle
			(at -0.40005 0)
			(size 0 0)
			(layers "F.Cu" "F.Mask" "F.Paste")
			(net "PVDDCR_SOC_P0")
		)
		(pad "2" smd circle
			(at 0.40005 0)
			(size 0 0)
			(layers "F.Cu" "F.Mask" "F.Paste")
			(net "GND")
		)
	)
	(footprint ""
		(layer "F.Cu")
		(at 156.83484 -93.174058 180)
		(property "Reference" "R3305"
			(at 0 0 180)
			(layer "F.SilkS")
			(hide yes)
			(effects
				(font
					(size 1.27 1.27)
				)
			)
		)
		(property "Value" ""
			(at 0 0 180)
			(layer "F.Fab")
			(effects
				(font
					(size 1.27 1.27)
				)
			)
		)
		(duplicate_pad_numbers_are_jumpers no)
		(fp_line
			(start 0.7874 0.4064)
			(end -0.7874 0.4064)
			(stroke
				(width 0.1524)
				(type default)
			)
			(layer "F.SilkS")
		)
		(fp_line
			(start 0.7874 -0.4064)
			(end 0.7874 0.4064)
			(stroke
				(width 0.1524)
				(type default)
			)
			(layer "F.SilkS")
		)
		(fp_line
			(start -0.7874 0.4064)
			(end -0.7874 -0.4064)
			(stroke
				(width 0.1524)
				(type default)
			)
			(layer "F.SilkS")
		)
		(fp_line
			(start -0.7874 -0.4064)
			(end 0.7874 -0.4064)
			(stroke
				(width 0.1524)
				(type default)
			)
			(layer "F.SilkS")
		)
		(fp_line
			(start 0.67945 0.3048)
			(end 0.120396 0.3048)
			(stroke
				(width 0.1)
				(type default)
			)
			(layer "F.Fab")
		)
		(fp_line
			(start 0.67945 -0.3048)
			(end 0.67945 0.3048)
			(stroke
				(width 0.1)
				(type default)
			)
			(layer "F.Fab")
		)
		(fp_line
			(start 0.12065 -0.2794)
			(end 0.12065 -0.3048)
			(stroke
				(width 0.1)
				(type default)
			)
			(layer "F.Fab")
		)
		(fp_line
			(start 0.12065 -0.3048)
			(end 0.67945 -0.3048)
			(stroke
				(width 0.1)
				(type default)
			)
			(layer "F.Fab")
		)
		(fp_line
			(start 0.120396 0.3048)
			(end 0.120396 0.2794)
			(stroke
				(width 0.1)
				(type default)
			)
			(layer "F.Fab")
		)
		(fp_line
			(start 0.120396 0.2794)
			(end -0.12065 0.2794)
			(stroke
				(width 0.1)
				(type default)
			)
			(layer "F.Fab")
		)
		(fp_line
			(start -0.12065 0.3048)
			(end -0.67945 0.3048)
			(stroke
				(width 0.1)
				(type default)
			)
			(layer "F.Fab")
		)
		(fp_line
			(start -0.12065 0.2794)
			(end -0.12065 0.3048)
			(stroke
				(width 0.1)
				(type default)
			)
			(layer "F.Fab")
		)
		(fp_line
			(start -0.12065 -0.2794)
			(end 0.12065 -0.2794)
			(stroke
				(width 0.1)
				(type default)
			)
			(layer "F.Fab")
		)
		(fp_line
			(start -0.12065 -0.305054)
			(end -0.12065 -0.2794)
			(stroke
				(width 0.1)
				(type default)
			)
			(layer "F.Fab")
		)
		(fp_line
			(start -0.67945 0.3048)
			(end -0.67945 -0.305054)
			(stroke
				(width 0.1)
				(type default)
			)
			(layer "F.Fab")
		)
		(fp_line
			(start -0.67945 -0.305054)
			(end -0.12065 -0.305054)
			(stroke
				(width 0.1)
				(type default)
			)
			(layer "F.Fab")
		)
		(pad "1" smd circle
			(at -0.40005 0 180)
			(size 0 0)
			(layers "F.Cu" "F.Mask" "F.Paste")
			(net "OCP_SFF_RBT_ARB_IN_MUX1")
		)
		(pad "2" smd circle
			(at 0.40005 0 180)
			(size 0 0)
			(layers "F.Cu" "F.Mask" "F.Paste")
			(net "OCP_SFF_RBT_ARB_IN_MUX1_R")
		)
	)
)
